# T6G (Grand Teton) — schematic netlist excerpt (pin names and nets, part order shuffled) for the footprints in the layout excerpt that follows; sources: Cadence DE-HDL packaged netlist, KiCad conversion of 04192023_DAF0TMB3IC0_F0TG_MB_C_brd_V02_OCP.brd

R1214  Q_RES  1K 1% CHIP  pkg 0201LF  page 186 : A = GND ; B = RT_ROM_MUX4_OE_N
R3238  Q_RES  33.2 1% CHIP  pkg 0402LF  page 150 : A = SMB_OCP_SFF_3V3AUX_SCL ; B = SMB_OCP_SFF_3V3AUX_SCL_R0
C6744  Q_CAP_DIFFBUS  DIFF BUS_0.22UF 6.3V 20% X6S  pkg C0201  page 352 : \1\ = P5E_CPU1_P3_TX_BUF_C_DN<9> ; \2\ = P5E_CPU1_P3_TX_BUF_DN<9>
R1116  Q_RES  4.7K 5% EMPTY  pkg 0201LF  page 309 : A = P1V8_CPU0_RT_1D ; B = TEST1_RT_CPU0_P3

(kicad_pcb
	(version 20260206)
	(generator "pcbnew")
	(generator_version "10.0")
	(general
		(thickness 1.6)
		(legacy_teardrops no)
	)
	(paper "A4")
	(title_block
		(title "04192023_DAF0TMB3IC0_F0TG_MB_C_brd_V02_OCP.brd")
		(comment 1 "Grand Teton / footprints 6097-6101 of 8354")
	)
	(layers
		(0 "F.Cu" signal "TOP")
		(4 "In1.Cu" signal "GND")
		(6 "In2.Cu" signal "IN1")
		(8 "In3.Cu" signal "GND1")
		(10 "In4.Cu" signal "IN2")
		(12 "In5.Cu" signal "GND2")
		(14 "In6.Cu" signal "IN3")
		(16 "In7.Cu" signal "GND3")
		(18 "In8.Cu" signal "VCC")
		(20 "In9.Cu" signal "VCC1")
		(22 "In10.Cu" signal "GND4")
		(24 "In11.Cu" signal "IN4")
		(26 "In12.Cu" signal "GND5")
		(28 "In13.Cu" signal "IN5")
		(30 "In14.Cu" signal "GND6")
		(32 "In15.Cu" signal "IN6")
		(34 "In16.Cu" signal "GND7")
		(2 "B.Cu" signal "BOTTOM")
		(9 "F.Adhes" user "F.Adhesive")
		(11 "B.Adhes" user "B.Adhesive")
		(13 "F.Paste" user "Package Geometry/Pastemask Top")
		(15 "B.Paste" user "Package Geometry/Pastemask Bottom")
		(5 "F.SilkS" user "Ref Des/Silkscreen Top")
		(7 "B.SilkS" user "Ref Des/Silkscreen Bottom")
		(1 "F.Mask" user "Board Geometry/Soldermask Top")
		(3 "B.Mask" user "Board Geometry/Soldermask Bottom")
		(17 "Dwgs.User" user "User.Drawings")
		(19 "Cmts.User" user "User.Comments")
		(21 "Eco1.User" user "User.Eco1")
		(23 "Eco2.User" user "User.Eco2")
		(25 "Edge.Cuts" user "Board Geometry/Outline")
		(27 "Margin" user)
		(31 "F.CrtYd" user "Package Geometry/Place Bound Top")
		(29 "B.CrtYd" user "Package Geometry/Place Bound Bottom")
		(35 "F.Fab" user "Ref Des/Assembly Top")
		(33 "B.Fab" user "Ref Des/Assembly Bottom")
	)
	(footprint ""
		(layer "B.Cu")
		(at 183.896 -20.378166 90)
		(property "Reference" "R3238"
			(at 0 0 90)
			(layer "B.SilkS")
			(hide yes)
			(effects
				(font
					(size 1.27 1.27)
				)
				(justify mirror)
			)
		)
		(property "Value" ""
			(at 0 0 90)
			(layer "B.Fab")
			(effects
				(font
					(size 1.27 1.27)
				)
				(justify mirror)
			)
		)
		(duplicate_pad_numbers_are_jumpers no)
		(fp_line
			(start 0.7874 -0.4064)
			(end -0.7874 -0.4064)
			(stroke
				(width 0.1524)
				(type default)
			)
			(layer "B.SilkS")
		)
		(fp_line
			(start -0.7874 -0.4064)
			(end -0.7874 0.4064)
			(stroke
				(width 0.1524)
				(type default)
			)
			(layer "B.SilkS")
		)
		(fp_line
			(start 0.7874 0.4064)
			(end 0.7874 -0.4064)
			(stroke
				(width 0.1524)
				(type default)
			)
			(layer "B.SilkS")
		)
		(fp_line
			(start -0.7874 0.4064)
			(end 0.7874 0.4064)
			(stroke
				(width 0.1524)
				(type default)
			)
			(layer "B.SilkS")
		)
		(fp_line
			(start 0.67945 -0.305054)
			(end 0.12065 -0.305054)
			(stroke
				(width 0.1)
				(type default)
			)
			(layer "B.Fab")
		)
		(fp_line
			(start 0.12065 -0.305054)
			(end 0.12065 -0.2794)
			(stroke
				(width 0.1)
				(type default)
			)
			(layer "B.Fab")
		)
		(fp_line
			(start -0.12065 -0.3048)
			(end -0.67945 -0.3048)
			(stroke
				(width 0.1)
				(type default)
			)
			(layer "B.Fab")
		)
		(fp_line
			(start -0.67945 -0.3048)
			(end -0.67945 0.3048)
			(stroke
				(width 0.1)
				(type default)
			)
			(layer "B.Fab")
		)
		(fp_line
			(start 0.12065 -0.2794)
			(end -0.12065 -0.2794)
			(stroke
				(width 0.1)
				(type default)
			)
			(layer "B.Fab")
		)
		(fp_line
			(start -0.12065 -0.2794)
			(end -0.12065 -0.3048)
			(stroke
				(width 0.1)
				(type default)
			)
			(layer "B.Fab")
		)
		(fp_line
			(start 0.12065 0.2794)
			(end 0.12065 0.3048)
			(stroke
				(width 0.1)
				(type default)
			)
			(layer "B.Fab")
		)
		(fp_line
			(start -0.120396 0.2794)
			(end 0.12065 0.2794)
			(stroke
				(width 0.1)
				(type default)
			)
			(layer "B.Fab")
		)
		(fp_line
			(start 0.67945 0.3048)
			(end 0.67945 -0.305054)
			(stroke
				(width 0.1)
				(type default)
			)
			(layer "B.Fab")
		)
		(fp_line
			(start 0.12065 0.3048)
			(end 0.67945 0.3048)
			(stroke
				(width 0.1)
				(type default)
			)
			(layer "B.Fab")
		)
		(fp_line
			(start -0.120396 0.3048)
			(end -0.120396 0.2794)
			(stroke
				(width 0.1)
				(type default)
			)
			(layer "B.Fab")
		)
		(fp_line
			(start -0.67945 0.3048)
			(end -0.120396 0.3048)
			(stroke
				(width 0.1)
				(type default)
			)
			(layer "B.Fab")
		)
		(pad "1" smd circle
			(at 0.40005 0 270)
			(size 0 0)
			(layers "B.Cu" "B.Mask" "B.Paste")
			(net "SMB_OCP_SFF_3V3AUX_SCL")
		)
		(pad "2" smd circle
			(at -0.40005 0 270)
			(size 0 0)
			(layers "B.Cu" "B.Mask" "B.Paste")
			(net "SMB_OCP_SFF_3V3AUX_SCL_R0")
		)
	)
	(footprint ""
		(layer "B.Cu")
		(at 161.94024 -419.262306)
		(property "Reference" "R1214"
			(at 0 0 0)
			(layer "B.SilkS")
			(hide yes)
			(effects
				(font
					(size 1.27 1.27)
				)
				(justify mirror)
			)
		)
		(property "Value" ""
			(at 0 0 0)
			(layer "B.Fab")
			(effects
				(font
					(size 1.27 1.27)
				)
				(justify mirror)
			)
		)
		(duplicate_pad_numbers_are_jumpers no)
		(fp_line
			(start -0.32512 -0.175006)
			(end -0.32512 0.175006)
			(stroke
				(width 0.1)
				(type default)
			)
			(layer "B.Fab")
		)
		(fp_line
			(start -0.32512 0.175006)
			(end 0.32512 0.175006)
			(stroke
				(width 0.1)
				(type default)
			)
			(layer "B.Fab")
		)
		(fp_line
			(start 0.32512 -0.175006)
			(end -0.32512 -0.175006)
			(stroke
				(width 0.1)
				(type default)
			)
			(layer "B.Fab")
		)
		(fp_line
			(start 0.32512 0.175006)
			(end 0.32512 -0.175006)
			(stroke
				(width 0.1)
				(type default)
			)
			(layer "B.Fab")
		)
		(pad "1" smd rect
			(at 0.2667 0 180)
			(size 0.3048 0.381)
			(layers "B.Cu" "B.Mask" "B.Paste")
			(net "GND")
		)
		(pad "2" smd rect
			(at -0.2667 0)
			(size 0.3048 0.381)
			(layers "B.Cu" "B.Mask" "B.Paste")
			(net "RT_ROM_MUX4_OE_N")
		)
	)
	(footprint ""
		(layer "B.Cu")
		(at 5.260086 -35.495484 180)
		(property "Reference" ""
			(at 0 0 0)
			(layer "B.SilkS")
			(hide yes)
			(effects
				(font
					(size 1.27 1.27)
				)
				(justify mirror)
			)
		)
		(property "Value" ""
			(at 0 0 0)
			(layer "B.Fab")
			(effects
				(font
					(size 1.27 1.27)
				)
				(justify mirror)
			)
		)
		(duplicate_pad_numbers_are_jumpers no)
		(pad "1" smd circle
			(at 0 0)
			(size 0.9906 0.9906)
			(layers "B.Cu" "B.Mask" "B.Paste")
			(net "Net_2236")
		)
		(zone
			(layer "B.Cu")
			(hatch none 0.5)
			(connect_pads
				(clearance 0)
			)
			(min_thickness 0.25)
			(keepout
				(tracks not_allowed)
				(vias allowed)
				(pads allowed)
				(copperpour not_allowed)
				(footprints allowed)
			)
			(placement
				(enabled no)
				(sheetname "")
			)
			(fill
				(thermal_gap 0.5)
				(thermal_bridge_width 0.5)
				(island_removal_mode 0)
			)
			(polygon
				(pts
					(arc
						(start 6.885686 -35.495484)
						(mid 3.634486 -35.495484)
						(end 6.885686 -35.495484)
					)
				)
			)
		)
	)
	(footprint ""
		(layer "B.Cu")
		(at 143.969486 -408.517344 90)
		(property "Reference" "C6744"
			(at 0 0 90)
			(layer "B.SilkS")
			(hide yes)
			(effects
				(font
					(size 1.27 1.27)
				)
				(justify mirror)
			)
		)
		(property "Value" ""
			(at 0 0 90)
			(layer "B.Fab")
			(effects
				(font
					(size 1.27 1.27)
				)
				(justify mirror)
			)
		)
		(duplicate_pad_numbers_are_jumpers no)
		(fp_line
			(start 0.299974 -0.150114)
			(end -0.299974 -0.150114)
			(stroke
				(width 0.1)
				(type default)
			)
			(layer "B.Fab")
		)
		(fp_line
			(start -0.299974 -0.150114)
			(end -0.299974 0.150114)
			(stroke
				(width 0.1)
				(type default)
			)
			(layer "B.Fab")
		)
		(fp_line
			(start 0.299974 0.150114)
			(end 0.299974 -0.150114)
			(stroke
				(width 0.1)
				(type default)
			)
			(layer "B.Fab")
		)
		(fp_line
			(start -0.299974 0.150114)
			(end 0.299974 0.150114)
			(stroke
				(width 0.1)
				(type default)
			)
			(layer "B.Fab")
		)
		(pad "1" smd rect
			(at 0.2667 0 270)
			(size 0.3048 0.381)
			(layers "B.Cu" "B.Mask" "B.Paste")
			(net "P5E_CPU1_P3_TX_BUF_C_DN<9>")
		)
		(pad "2" smd rect
			(at -0.2667 0 270)
			(size 0.3048 0.381)
			(layers "B.Cu" "B.Mask" "B.Paste")
			(net "P5E_CPU1_P3_TX_BUF_DN<9>")
		)
	)
	(footprint ""
		(layer "B.Cu")
		(at 365.09579 -393.04468 180)
		(property "Reference" "R1116"
			(at 0 0 0)
			(layer "B.SilkS")
			(hide yes)
			(effects
				(font
					(size 1.27 1.27)
				)
				(justify mirror)
			)
		)
		(property "Value" ""
			(at 0 0 0)
			(layer "B.Fab")
			(effects
				(font
					(size 1.27 1.27)
				)
				(justify mirror)
			)
		)
		(duplicate_pad_numbers_are_jumpers no)
		(fp_line
			(start 0.32512 0.175006)
			(end 0.32512 -0.175006)
			(stroke
				(width 0.1)
				(type default)
			)
			(layer "B.Fab")
		)
		(fp_line
			(start 0.32512 -0.175006)
			(end -0.32512 -0.175006)
			(stroke
				(width 0.1)
				(type default)
			)
			(layer "B.Fab")
		)
		(fp_line
			(start -0.32512 0.175006)
			(end 0.32512 0.175006)
			(stroke
				(width 0.1)
				(type default)
			)
			(layer "B.Fab")
		)
		(fp_line
			(start -0.32512 -0.175006)
			(end -0.32512 0.175006)
			(stroke
				(width 0.1)
				(type default)
			)
			(layer "B.Fab")
		)
		(pad "1" smd rect
			(at 0.2667 0)
			(size 0.3048 0.381)
			(layers "B.Cu" "B.Mask" "B.Paste")
			(net "P1V8_CPU0_RT_1D")
		)
		(pad "2" smd rect
			(at -0.2667 0 180)
			(size 0.3048 0.381)
			(layers "B.Cu" "B.Mask" "B.Paste")
			(net "TEST1_RT_CPU0_P3")
		)
	)
)
